# SCM (Grand Teton) — schematic netlist excerpt (pin names and nets, part order shuffled) for the footprints in the layout excerpt that follows; sources: Cadence DE-HDL packaged netlist, KiCad conversion of 12092022_DA0F0TMDCD0_F0T_Management_Board_D_brd_V3_OCP.brd

R401  Q_RES  33.2 1% CHIP  pkg 0402LF  page 13 : A = PU_BMC_FWSPIABR_N ; B = PU_BMC_FWSPIABR_N_R
R340  Q_RES  120 1% CHIP  pkg 0402LF  page 20 : A = GND ; B = M_BMC_DDR4_MWE_N

(kicad_pcb
	(version 20260206)
	(generator "pcbnew")
	(generator_version "10.0")
	(general
		(thickness 1.6)
		(legacy_teardrops no)
	)
	(paper "A4")
	(title_block
		(title "12092022_DA0F0TMDCD0_F0T_Management_Board_D_brd_V3_OCP.brd")
		(comment 1 "Grand Teton / footprints 1195-1196 of 1440")
	)
	(layers
		(0 "F.Cu" signal "TOP")
		(4 "In1.Cu" signal "GND")
		(6 "In2.Cu" signal "IN1")
		(8 "In3.Cu" signal "GND1")
		(10 "In4.Cu" signal "IN2")
		(12 "In5.Cu" signal "VCC")
		(14 "In6.Cu" signal "VCC1")
		(16 "In7.Cu" signal "IN3")
		(18 "In8.Cu" signal "GND2")
		(20 "In9.Cu" signal "IN4")
		(22 "In10.Cu" signal "GND3")
		(2 "B.Cu" signal "BOTTOM")
		(9 "F.Adhes" user "F.Adhesive")
		(11 "B.Adhes" user "B.Adhesive")
		(13 "F.Paste" user "Package Geometry/Pastemask Top")
		(15 "B.Paste" user "Package Geometry/Pastemask Bottom")
		(5 "F.SilkS" user "Ref Des/Silkscreen Top")
		(7 "B.SilkS" user "Ref Des/Silkscreen Bottom")
		(1 "F.Mask" user "Board Geometry/Soldermask Top")
		(3 "B.Mask" user "Board Geometry/Soldermask Bottom")
		(17 "Dwgs.User" user "User.Drawings")
		(19 "Cmts.User" user "User.Comments")
		(21 "Eco1.User" user "User.Eco1")
		(23 "Eco2.User" user "User.Eco2")
		(25 "Edge.Cuts" user "Board Geometry/Outline")
		(27 "Margin" user)
		(31 "F.CrtYd" user "Package Geometry/Place Bound Top")
		(29 "B.CrtYd" user "Package Geometry/Place Bound Bottom")
		(35 "F.Fab" user "Ref Des/Assembly Top")
		(33 "B.Fab" user "Ref Des/Assembly Bottom")
	)
	(footprint ""
		(layer "B.Cu")
		(at 83.16722 -40.490394)
		(property "Reference" "R340"
			(at 0 0 0)
			(layer "B.SilkS")
			(hide yes)
			(effects
				(font
					(size 1.27 1.27)
				)
				(justify mirror)
			)
		)
		(property "Value" ""
			(at 0 0 0)
			(layer "B.Fab")
			(effects
				(font
					(size 1.27 1.27)
				)
				(justify mirror)
			)
		)
		(duplicate_pad_numbers_are_jumpers no)
		(fp_line
			(start -0.7874 -0.4064)
			(end -0.7874 0.4064)
			(stroke
				(width 0.1524)
				(type default)
			)
			(layer "B.SilkS")
		)
		(fp_line
			(start -0.7874 0.4064)
			(end 0.7874 0.4064)
			(stroke
				(width 0.1524)
				(type default)
			)
			(layer "B.SilkS")
		)
		(fp_line
			(start 0.7874 -0.4064)
			(end -0.7874 -0.4064)
			(stroke
				(width 0.1524)
				(type default)
			)
			(layer "B.SilkS")
		)
		(fp_line
			(start 0.7874 0.4064)
			(end 0.7874 -0.4064)
			(stroke
				(width 0.1524)
				(type default)
			)
			(layer "B.SilkS")
		)
		(fp_line
			(start -0.67945 -0.3048)
			(end -0.67945 0.3048)
			(stroke
				(width 0.1)
				(type default)
			)
			(layer "B.Fab")
		)
		(fp_line
			(start -0.67945 0.3048)
			(end -0.120396 0.3048)
			(stroke
				(width 0.1)
				(type default)
			)
			(layer "B.Fab")
		)
		(fp_line
			(start -0.12065 -0.3048)
			(end -0.67945 -0.3048)
			(stroke
				(width 0.1)
				(type default)
			)
			(layer "B.Fab")
		)
		(fp_line
			(start -0.12065 -0.2794)
			(end -0.12065 -0.3048)
			(stroke
				(width 0.1)
				(type default)
			)
			(layer "B.Fab")
		)
		(fp_line
			(start -0.120396 0.2794)
			(end 0.12065 0.2794)
			(stroke
				(width 0.1)
				(type default)
			)
			(layer "B.Fab")
		)
		(fp_line
			(start -0.120396 0.3048)
			(end -0.120396 0.2794)
			(stroke
				(width 0.1)
				(type default)
			)
			(layer "B.Fab")
		)
		(fp_line
			(start 0.12065 -0.305054)
			(end 0.12065 -0.2794)
			(stroke
				(width 0.1)
				(type default)
			)
			(layer "B.Fab")
		)
		(fp_line
			(start 0.12065 -0.2794)
			(end -0.12065 -0.2794)
			(stroke
				(width 0.1)
				(type default)
			)
			(layer "B.Fab")
		)
		(fp_line
			(start 0.12065 0.2794)
			(end 0.12065 0.3048)
			(stroke
				(width 0.1)
				(type default)
			)
			(layer "B.Fab")
		)
		(fp_line
			(start 0.12065 0.3048)
			(end 0.67945 0.3048)
			(stroke
				(width 0.1)
				(type default)
			)
			(layer "B.Fab")
		)
		(fp_line
			(start 0.67945 -0.305054)
			(end 0.12065 -0.305054)
			(stroke
				(width 0.1)
				(type default)
			)
			(layer "B.Fab")
		)
		(fp_line
			(start 0.67945 0.3048)
			(end 0.67945 -0.305054)
			(stroke
				(width 0.1)
				(type default)
			)
			(layer "B.Fab")
		)
		(pad "1" smd circle
			(at 0.40005 0 180)
			(size 0 0)
			(layers "B.Cu" "B.Mask" "B.Paste")
			(net "GND")
		)
		(pad "2" smd circle
			(at -0.40005 0 180)
			(size 0 0)
			(layers "B.Cu" "B.Mask" "B.Paste")
			(net "M_BMC_DDR4_MWE_N")
		)
	)
	(footprint ""
		(layer "B.Cu")
		(at 56.134 -62.4332 180)
		(property "Reference" "R401"
			(at 0 0 0)
			(layer "B.SilkS")
			(hide yes)
			(effects
				(font
					(size 1.27 1.27)
				)
				(justify mirror)
			)
		)
		(property "Value" ""
			(at 0 0 0)
			(layer "B.Fab")
			(effects
				(font
					(size 1.27 1.27)
				)
				(justify mirror)
			)
		)
		(duplicate_pad_numbers_are_jumpers no)
		(fp_line
			(start 0.7874 0.4064)
			(end 0.7874 -0.4064)
			(stroke
				(width 0.1524)
				(type default)
			)
			(layer "B.SilkS")
		)
		(fp_line
			(start 0.7874 -0.4064)
			(end -0.7874 -0.4064)
			(stroke
				(width 0.1524)
				(type default)
			)
			(layer "B.SilkS")
		)
		(fp_line
			(start -0.7874 0.4064)
			(end 0.7874 0.4064)
			(stroke
				(width 0.1524)
				(type default)
			)
			(layer "B.SilkS")
		)
		(fp_line
			(start -0.7874 -0.4064)
			(end -0.7874 0.4064)
			(stroke
				(width 0.1524)
				(type default)
			)
			(layer "B.SilkS")
		)
		(fp_line
			(start 0.67945 0.3048)
			(end 0.67945 -0.305054)
			(stroke
				(width 0.1)
				(type default)
			)
			(layer "B.Fab")
		)
		(fp_line
			(start 0.67945 -0.305054)
			(end 0.12065 -0.305054)
			(stroke
				(width 0.1)
				(type default)
			)
			(layer "B.Fab")
		)
		(fp_line
			(start 0.12065 0.3048)
			(end 0.67945 0.3048)
			(stroke
				(width 0.1)
				(type default)
			)
			(layer "B.Fab")
		)
		(fp_line
			(start 0.12065 0.2794)
			(end 0.12065 0.3048)
			(stroke
				(width 0.1)
				(type default)
			)
			(layer "B.Fab")
		)
		(fp_line
			(start 0.12065 -0.2794)
			(end -0.12065 -0.2794)
			(stroke
				(width 0.1)
				(type default)
			)
			(layer "B.Fab")
		)
		(fp_line
			(start 0.12065 -0.305054)
			(end 0.12065 -0.2794)
			(stroke
				(width 0.1)
				(type default)
			)
			(layer "B.Fab")
		)
		(fp_line
			(start -0.120396 0.3048)
			(end -0.120396 0.2794)
			(stroke
				(width 0.1)
				(type default)
			)
			(layer "B.Fab")
		)
		(fp_line
			(start -0.120396 0.2794)
			(end 0.12065 0.2794)
			(stroke
				(width 0.1)
				(type default)
			)
			(layer "B.Fab")
		)
		(fp_line
			(start -0.12065 -0.2794)
			(end -0.12065 -0.3048)
			(stroke
				(width 0.1)
				(type default)
			)
			(layer "B.Fab")
		)
		(fp_line
			(start -0.12065 -0.3048)
			(end -0.67945 -0.3048)
			(stroke
				(width 0.1)
				(type default)
			)
			(layer "B.Fab")
		)
		(fp_line
			(start -0.67945 0.3048)
			(end -0.120396 0.3048)
			(stroke
				(width 0.1)
				(type default)
			)
			(layer "B.Fab")
		)
		(fp_line
			(start -0.67945 -0.3048)
			(end -0.67945 0.3048)
			(stroke
				(width 0.1)
				(type default)
			)
			(layer "B.Fab")
		)
		(pad "1" smd circle
			(at 0.40005 0)
			(size 0 0)
			(layers "B.Cu" "B.Mask" "B.Paste")
			(net "PU_BMC_FWSPIABR_N")
		)
		(pad "2" smd circle
			(at -0.40005 0)
			(size 0 0)
			(layers "B.Cu" "B.Mask" "B.Paste")
			(net "PU_BMC_FWSPIABR_N_R")
		)
	)
)
